(kicad_pcb
	(version 20241229)
	(generator "pcbnew")
	(generator_version "9.0")
	(general
		(thickness 1.711)
		(legacy_teardrops no)
	)
	(paper "A4")
	(title_block
		(title "Antmicro Baseboard for Jetson AGX Thor")
		(date "2026-02-18")
		(rev "1.1.0")
		(company "Antmicro Ltd")
		(comment 1 "www.antmicro.com")
		(comment 9 "footprints 108-109 of 1170")
	)
	(layers
		(0 "F.Cu" signal)
		(4 "In1.Cu" signal)
		(6 "In2.Cu" signal)
		(8 "In3.Cu" signal)
		(10 "In4.Cu" jumper)
		(12 "In5.Cu" signal)
		(14 "In6.Cu" signal)
		(16 "In7.Cu" signal)
		(18 "In8.Cu" signal)
		(2 "B.Cu" signal)
		(9 "F.Adhes" user "F.Adhesive")
		(11 "B.Adhes" user "B.Adhesive")
		(13 "F.Paste" user)
		(15 "B.Paste" user)
		(5 "F.SilkS" user "F.Silkscreen")
		(7 "B.SilkS" user "B.Silkscreen")
		(1 "F.Mask" user)
		(3 "B.Mask" user)
		(17 "Dwgs.User" user "User.Drawings")
		(19 "Cmts.User" user "User.Comments")
		(21 "Eco1.User" user "User.Eco1")
		(23 "Eco2.User" user "User.Eco2")
		(25 "Edge.Cuts" user)
		(27 "Margin" user)
		(31 "F.CrtYd" user "F.Courtyard")
		(29 "B.CrtYd" user "B.Courtyard")
		(35 "F.Fab" user)
		(33 "B.Fab" user)
	)
	(footprint "antmicro-footprints:C_0402_1005Metric"
		(layer "F.Cu")
		(at 206 77.9 180)
		(descr "Capacitor SMD 0402")
		(tags "capacitor SMD 0402")
		(property "Reference" "C121"
			(at -3.730532 0.36 0)
			(layer "F.SilkS")
			(effects
				(font
					(size 0.7 0.7)
					(thickness 0.15)
				)
				(justify right top)
			)
		)
		(property "Value" "C_10u_0402"
			(at -1.022927 2.155213 0)
			(layer "F.Fab")
			(effects
				(font
					(size 0.7 0.7)
					(thickness 0.15)
				)
				(justify right top)
			)
		)
		(property "Datasheet" "https://www.yageo.com/en/Chart/Download/pdf/CC0402MRX5R5BB106"
			(at 0 0 0)
			(layer "F.Fab")
			(hide yes)
			(effects
				(font
					(size 1.27 1.27)
					(thickness 0.15)
				)
			)
		)
		(property "Description" "SMD Multilayer Ceramic Capacitor, 10 µF, 6.3 V, 0402 [1005 Metric], ± 20%, X5R, CC Series"
			(at 0 0 0)
			(layer "F.Fab")
			(hide yes)
			(effects
				(font
					(size 1.27 1.27)
					(thickness 0.15)
				)
			)
		)
		(property "MPN" "CC0402MRX5R5BB106"
			(at 0 0 180)
			(unlocked yes)
			(layer "F.Fab")
			(hide yes)
			(effects
				(font
					(size 1 1)
					(thickness 0.15)
				)
			)
		)
		(property "Manufacturer" "YAGEO"
			(at 0 0 180)
			(unlocked yes)
			(layer "F.Fab")
			(hide yes)
			(effects
				(font
					(size 1 1)
					(thickness 0.15)
				)
			)
		)
		(property "License" "Apache-2.0"
			(at 0 0 180)
			(unlocked yes)
			(layer "F.Fab")
			(hide yes)
			(effects
				(font
					(size 1 1)
					(thickness 0.15)
				)
			)
		)
		(property "Author" "Antmicro"
			(at 0 0 180)
			(unlocked yes)
			(layer "F.Fab")
			(hide yes)
			(effects
				(font
					(size 1 1)
					(thickness 0.15)
				)
			)
		)
		(property "Val" "10u"
			(at 0 0 180)
			(unlocked yes)
			(layer "F.Fab")
			(hide yes)
			(effects
				(font
					(size 1 1)
					(thickness 0.15)
				)
			)
		)
		(property "Voltage" ""
			(at 0 0 180)
			(unlocked yes)
			(layer "F.Fab")
			(hide yes)
			(effects
				(font
					(size 1 1)
					(thickness 0.15)
				)
			)
		)
		(property "Dielectric" ""
			(at 0 0 180)
			(unlocked yes)
			(layer "F.Fab")
			(hide yes)
			(effects
				(font
					(size 1 1)
					(thickness 0.15)
				)
			)
		)
		(sheetname "/USB Debug, PD/")
		(sheetfile "usb_debug_pd.kicad_sch")
		(attr smd)
		(fp_rect
			(start -0.925 -0.47)
			(end 0.925 0.47)
			(stroke
				(width 0.05)
				(type default)
			)
			(fill no)
			(layer "F.CrtYd")
		)
		(fp_line
			(start 0.504 0.248)
			(end -0.494 0.248)
			(stroke
				(width 0.15)
				(type solid)
			)
			(layer "F.Fab")
		)
		(fp_line
			(start 0.504 -0.25)
			(end 0.504 0.248)
			(stroke
				(width 0.15)
				(type solid)
			)
			(layer "F.Fab")
		)
		(fp_line
			(start -0.494 0.248)
			(end -0.494 -0.25)
			(stroke
				(width 0.15)
				(type solid)
			)
			(layer "F.Fab")
		)
		(fp_line
			(start -0.494 -0.25)
			(end 0.504 -0.25)
			(stroke
				(width 0.15)
				(type solid)
			)
			(layer "F.Fab")
		)
		(fp_text user "${REFERENCE}"
			(at -0.939 4.599 0)
			(layer "F.Fab")
			(effects
				(font
					(size 0.7 0.7)
					(thickness 0.15)
				)
				(justify right top)
			)
		)
		(fp_text user "Author: Antmicro"
			(at -0.939 3.399 0)
			(layer "F.Fab")
			(effects
				(font
					(size 0.7 0.7)
					(thickness 0.15)
				)
				(justify right top)
			)
		)
		(fp_text user "License: Apache-2.0"
			(at -0.939 5.799 0)
			(layer "F.Fab")
			(effects
				(font
					(size 0.7 0.7)
					(thickness 0.15)
				)
				(justify right top)
			)
		)
		(pad "1" smd roundrect
			(at -0.48 0 180)
			(size 0.59 0.64)
			(layers "F.Cu" "F.Mask" "F.Paste")
			(roundrect_rratio 0.25)
			(net 1 "GND")
			(pintype "passive")
		)
		(pad "2" smd roundrect
			(at 0.48 0 180)
			(size 0.59 0.64)
			(layers "F.Cu" "F.Mask" "F.Paste")
			(roundrect_rratio 0.25)
			(net 294 "/USB Debug, PD/PDC_LDO_3V3")
			(pintype "passive")
		)
	)
	(footprint "antmicro-footprints:Spacer_Drill4.45mm_H4mm_9774040960R"
		(locked yes)
		(layer "F.Cu")
		(at 76.930532 149.71 90)
		(property "Reference" "H5"
			(at -3.48 -3.6 90)
			(layer "F.SilkS")
			(effects
				(font
					(size 0.7 0.7)
					(thickness 0.15)
				)
				(justify left bottom)
			)
		)
		(property "Value" "Spacer_Drill4.45mm_H4mm_9774040960R"
			(at -3.95 5.05 90)
			(layer "F.Fab")
			(effects
				(font
					(size 0.7 0.7)
					(thickness 0.15)
				)
				(justify left bottom)
			)
		)
		(property "Datasheet" "https://www.we-online.com/components/products/datasheet/9774040960R.pdf"
			(at 0 0 90)
			(layer "F.Fab")
			(effects
				(font
					(size 0.7 0.7)
					(thickness 0.15)
				)
				(justify left bottom)
			)
		)
		(property "Description" "Spacer, SMT, Non Stop, Steel, Swage Round, 6 mm x 4 mm, 3.3 mm Internal, WA-SMST Series"
			(at 0 0 90)
			(layer "F.Fab")
			(effects
				(font
					(size 0.7 0.7)
					(thickness 0.15)
				)
				(justify left bottom)
			)
		)
		(property "Manufacturer" "Würth Elektronik"
			(at 0 0 90)
			(unlocked yes)
			(layer "F.Fab")
			(hide yes)
			(effects
				(font
					(size 1 1)
					(thickness 0.15)
				)
			)
		)
		(property "MPN" "9774040960R"
			(at 0 0 90)
			(unlocked yes)
			(layer "F.Fab")
			(hide yes)
			(effects
				(font
					(size 1 1)
					(thickness 0.15)
				)
			)
		)
		(property "Author" "Antmicro"
			(at 0 0 90)
			(unlocked yes)
			(layer "F.Fab")
			(hide yes)
			(effects
				(font
					(size 1 1)
					(thickness 0.15)
				)
			)
		)
		(property "License" "Apache-2.0"
			(at 0 0 90)
			(unlocked yes)
			(layer "F.Fab")
			(hide yes)
			(effects
				(font
					(size 1 1)
					(thickness 0.15)
				)
			)
		)
		(sheetname "/SoM_Power/")
		(sheetfile "som_power.kicad_sch")
		(attr smd)
		(fp_rect
			(start -3.95 -3.95)
			(end 3.95 3.95)
			(stroke
				(width 0.05)
				(type solid)
			)
			(fill no)
			(layer "F.CrtYd")
		)
		(fp_circle
			(center 0 0)
			(end 3.25 0)
			(stroke
				(width 0.05)
				(type solid)
			)
			(fill no)
			(layer "F.CrtYd")
		)
		(fp_circle
			(center 0 0)
			(end 2.564 0)
			(stroke
				(width 0.15)
				(type solid)
			)
			(fill no)
			(layer "F.Fab")
		)
		(fp_text user "License: Apache-2.0"
			(at -3.95 6.25 90)
			(layer "F.Fab")
			(effects
				(font
					(size 0.7 0.7)
					(thickness 0.15)
				)
				(justify left bottom)
			)
		)
		(fp_text user "${REFERENCE}"
			(at -3.95 7.45 90)
			(layer "F.Fab")
			(effects
				(font
					(size 0.7 0.7)
					(thickness 0.15)
				)
				(justify left bottom)
			)
		)
		(fp_text user "Author: Antmicro"
			(at -3.95 8.65 90)
			(layer "F.Fab")
			(effects
				(font
					(size 0.7 0.7)
					(thickness 0.15)
				)
				(justify left bottom)
			)
		)
		(pad "" smd custom
			(at -2.55 -0.55 212.5)
			(size 0.1 0.1)
			(layers "F.Paste")
			(options
				(clearance outline)
				(anchor circle)
			)
			(primitives
				(gr_arc
					(start 0 0)
					(mid 0.704278 1.28373)
					(end 0.608513 2.744826)
					(width 0.7)
				)
			)
		)
		(pad "" smd custom
			(at -0.55 2.55 302.5)
			(size 0.1 0.1)
			(layers "F.Paste")
			(options
				(clearance outline)
				(anchor circle)
			)
			(primitives
				(gr_arc
					(start 0 0)
					(mid 0.704278 1.28373)
					(end 0.608513 2.744826)
					(width 0.7)
				)
			)
		)
		(pad "" smd custom
			(at 0.55 -2.55 122.5)
			(size 0.1 0.1)
			(layers "F.Paste")
			(options
				(clearance outline)
				(anchor circle)
			)
			(primitives
				(gr_arc
					(start 0 0)
					(mid 0.704278 1.28373)
					(end 0.608513 2.744826)
					(width 0.7)
				)
			)
		)
		(pad "" smd custom
			(at 2.55 0.55 32.5)
			(size 0.1 0.1)
			(layers "F.Paste")
			(options
				(clearance outline)
				(anchor circle)
			)
			(primitives
				(gr_arc
					(start 0 0)
					(mid 0.704278 1.28373)
					(end 0.608513 2.744826)
					(width 0.7)
				)
			)
		)
		(pad "1" thru_hole circle
			(at 0 0 90)
			(size 7.4 7.4)
			(drill 4.45)
			(layers "*.Cu" "*.Mask")
			(remove_unused_layers no)
			(net 1 "GND")
			(pintype "passive")
		)
	)
)
